# TIMECARD (Time Appliance Project (Time Card)) — schematic netlist excerpt (pin names and nets, part order shuffled) for the footprints in the layout excerpt that follows; sources: Cadence DE-HDL packaged netlist, KiCad conversion of R4006-B0001-02_R01.brd

R288  RESISTOR  4.7KOHM 1%  pkg SMC_0402R_H016  page 11 : \1\ = SG ; \2\ = FPGA_IN_MAC_BITEOUT
SP36  SOLDER_PREFORM  pkg 0201_SOLDER_PREFORM_4MIL  page 34 : \1\ = NC ; \2\ = NC
C226  CAPACITOR  0.1UF 25V 10% X7R  pkg SMC_0402R_H022  page 31 : \1\ = XP3R3V ; \2\ = SG

(kicad_pcb
	(version 20260206)
	(generator "pcbnew")
	(generator_version "10.0")
	(general
		(thickness 1.6)
		(legacy_teardrops no)
	)
	(paper "A4")
	(title_block
		(title "timecard-production-celestica-r4006 — R4006-B0001-02_R01.brd")
		(comment 1 "Time Appliance Project (Time Card) / footprints 78-80 of 1113")
	)
	(layers
		(0 "F.Cu" signal "TOP")
		(4 "In1.Cu" signal "L02_GND1")
		(6 "In2.Cu" signal "L03_SIG1")
		(8 "In3.Cu" signal "L04_GND2")
		(10 "In4.Cu" signal "L05_VCC1")
		(12 "In5.Cu" signal "L06_VCC2")
		(14 "In6.Cu" signal "L07_GND3")
		(16 "In7.Cu" signal "L08_SIG2")
		(18 "In8.Cu" signal "L09_GND4")
		(2 "B.Cu" signal "BOTTOM")
		(9 "F.Adhes" user "F.Adhesive")
		(11 "B.Adhes" user "B.Adhesive")
		(13 "F.Paste" user "Package Geometry/Pastemask Top")
		(15 "B.Paste" user "Package Geometry/Pastemask Bottom")
		(5 "F.SilkS" user "Ref Des/Silkscreen Top")
		(7 "B.SilkS" user "Ref Des/Silkscreen Bottom")
		(1 "F.Mask" user "Board Geometry/Soldermask Top")
		(3 "B.Mask" user "Board Geometry/Soldermask Bottom")
		(17 "Dwgs.User" user "User.Drawings")
		(19 "Cmts.User" user "User.Comments")
		(21 "Eco1.User" user "User.Eco1")
		(23 "Eco2.User" user "User.Eco2")
		(25 "Edge.Cuts" user "Board Geometry/Outline")
		(27 "Margin" user)
		(31 "F.CrtYd" user "Package Geometry/Place Bound Top")
		(29 "B.CrtYd" user "Package Geometry/Place Bound Bottom")
		(35 "F.Fab" user "Ref Des/Assembly Top")
		(33 "B.Fab" user "Ref Des/Assembly Bottom")
	)
	(footprint ""
		(layer "F.Cu")
		(at 143.256 -24.511 -90)
		(property "Reference" "C226"
			(at -3.429 0.08763 90)
			(unlocked yes)
			(layer "F.SilkS")
			(effects
				(font
					(size 0.7874 0.5842)
					(thickness 0.1524)
				)
			)
		)
		(property "Value" "VAL*"
			(at 0.0762 2.067306 270)
			(unlocked yes)
			(layer "F.Fab")
			(hide yes)
			(effects
				(font
					(size 0.7874 0.5842)
					(thickness 0.1524)
				)
			)
		)
		(property "Tolerance" "TOL*"
			(at 0.0762 3.032506 270)
			(unlocked yes)
			(layer "Cmts.User")
			(hide yes)
			(effects
				(font
					(size 0.7874 0.5842)
					(thickness 0.1524)
				)
			)
		)
		(property "User Part Number" "PARTNUM*"
			(at 0.1016 4.023106 270)
			(unlocked yes)
			(layer "Cmts.User")
			(hide yes)
			(effects
				(font
					(size 0.7874 0.5842)
					(thickness 0.1524)
				)
			)
		)
		(property "Device Type" "CAPACITOR-G105-0B104-EK,0.1UF,A"
			(at 0.0508 1.127506 270)
			(unlocked yes)
			(layer "F.Fab")
			(hide yes)
			(effects
				(font
					(size 0.7874 0.5842)
					(thickness 0.1524)
				)
			)
		)
		(duplicate_pad_numbers_are_jumpers no)
		(fp_line
			(start -1.143 0.5588)
			(end 1.143 0.5588)
			(stroke
				(width 0.1)
				(type default)
			)
			(layer "F.SilkS")
		)
		(fp_line
			(start 1.143 0.5588)
			(end 1.143 -0.5588)
			(stroke
				(width 0.1)
				(type default)
			)
			(layer "F.SilkS")
		)
		(fp_line
			(start -1.143 -0.5588)
			(end -1.143 0.5588)
			(stroke
				(width 0.1)
				(type default)
			)
			(layer "F.SilkS")
		)
		(fp_line
			(start 1.143 -0.5588)
			(end -1.143 -0.5588)
			(stroke
				(width 0.1)
				(type default)
			)
			(layer "F.SilkS")
		)
		(fp_rect
			(start -1.143 0.5588)
			(end 1.143 -0.5588)
			(stroke
				(width 0)
				(type default)
			)
			(fill no)
			(layer "F.CrtYd")
		)
		(fp_line
			(start -0.508 0.3048)
			(end 0.508 0.3048)
			(stroke
				(width 0.1)
				(type default)
			)
			(layer "F.Fab")
		)
		(fp_line
			(start 0.508 0.3048)
			(end 0.508 -0.3048)
			(stroke
				(width 0.1)
				(type default)
			)
			(layer "F.Fab")
		)
		(fp_line
			(start -0.508 -0.3048)
			(end -0.508 0.3048)
			(stroke
				(width 0.1)
				(type default)
			)
			(layer "F.Fab")
		)
		(fp_line
			(start 0.508 -0.3048)
			(end -0.508 -0.3048)
			(stroke
				(width 0.1)
				(type default)
			)
			(layer "F.Fab")
		)
		(pad "1" smd rect
			(at -0.5334 0 270)
			(size 0.7112 0.6096)
			(layers "F.Cu" "F.Mask" "F.Paste")
			(net "XP3R3V")
		)
		(pad "2" smd rect
			(at 0.5334 0 270)
			(size 0.7112 0.6096)
			(layers "F.Cu" "F.Mask" "F.Paste")
			(net "SG")
		)
		(zone
			(layer "F.Cu")
			(hatch none 0.5)
			(connect_pads
				(clearance 0)
			)
			(min_thickness 0.25)
			(keepout
				(tracks allowed)
				(vias not_allowed)
				(pads allowed)
				(copperpour not_allowed)
				(footprints allowed)
			)
			(placement
				(enabled no)
				(sheetname "")
			)
			(fill
				(thermal_gap 0.5)
				(thermal_bridge_width 0.5)
				(island_removal_mode 0)
			)
			(polygon
				(pts
					(xy 142.9512 -24.5872) (xy 142.9512 -24.4348) (xy 143.5608 -24.4348) (xy 143.5608 -24.5872)
				)
			)
		)
	)
	(footprint ""
		(layer "F.Cu")
		(at 124.587 -42.545 180)
		(property "Reference" "R288"
			(at -3.048 1.35763 0)
			(unlocked yes)
			(layer "F.SilkS")
			(effects
				(font
					(size 0.7874 0.5842)
					(thickness 0.1524)
				)
			)
		)
		(property "Value" "VAL*"
			(at 0.02032 2.13233 180)
			(unlocked yes)
			(layer "F.Fab")
			(hide yes)
			(effects
				(font
					(size 0.7874 0.5842)
					(thickness 0.1524)
				)
			)
		)
		(property "Tolerance" "TOL*"
			(at 0.044704 3.05435 180)
			(unlocked yes)
			(layer "Cmts.User")
			(hide yes)
			(effects
				(font
					(size 0.7874 0.5842)
					(thickness 0.1524)
				)
			)
		)
		(property "User Part Number" "PARTNUM*"
			(at 0.02032 4.024884 180)
			(unlocked yes)
			(layer "Cmts.User")
			(hide yes)
			(effects
				(font
					(size 0.7874 0.5842)
					(thickness 0.1524)
				)
			)
		)
		(property "Device Type" "RESISTOR-G155-14701-01,4.7KOHMA"
			(at 0.008382 1.210564 180)
			(unlocked yes)
			(layer "F.Fab")
			(hide yes)
			(effects
				(font
					(size 0.7874 0.5842)
					(thickness 0.1524)
				)
			)
		)
		(duplicate_pad_numbers_are_jumpers no)
		(fp_line
			(start 1.143 0.5588)
			(end 1.143 -0.5588)
			(stroke
				(width 0.1)
				(type default)
			)
			(layer "F.SilkS")
		)
		(fp_line
			(start 1.143 -0.5588)
			(end -1.143 -0.5588)
			(stroke
				(width 0.1)
				(type default)
			)
			(layer "F.SilkS")
		)
		(fp_line
			(start -1.143 0.5588)
			(end 1.143 0.5588)
			(stroke
				(width 0.1)
				(type default)
			)
			(layer "F.SilkS")
		)
		(fp_line
			(start -1.143 -0.5588)
			(end -1.143 0.5588)
			(stroke
				(width 0.1)
				(type default)
			)
			(layer "F.SilkS")
		)
		(fp_rect
			(start 1.143 0.5588)
			(end -1.143 -0.5588)
			(stroke
				(width 0)
				(type default)
			)
			(fill no)
			(layer "F.CrtYd")
		)
		(fp_line
			(start 0.508 0.3048)
			(end 0.508 -0.3048)
			(stroke
				(width 0.1)
				(type default)
			)
			(layer "F.Fab")
		)
		(fp_line
			(start 0.508 -0.3048)
			(end -0.508 -0.3048)
			(stroke
				(width 0.1)
				(type default)
			)
			(layer "F.Fab")
		)
		(fp_line
			(start -0.508 0.3048)
			(end 0.508 0.3048)
			(stroke
				(width 0.1)
				(type default)
			)
			(layer "F.Fab")
		)
		(fp_line
			(start -0.508 -0.3048)
			(end -0.508 0.3048)
			(stroke
				(width 0.1)
				(type default)
			)
			(layer "F.Fab")
		)
		(pad "1" smd rect
			(at -0.5334 0 180)
			(size 0.7112 0.6096)
			(layers "F.Cu" "F.Mask" "F.Paste")
			(net "SG")
		)
		(pad "2" smd rect
			(at 0.5334 0 180)
			(size 0.7112 0.6096)
			(layers "F.Cu" "F.Mask" "F.Paste")
			(net "FPGA_IN_MAC_BITEOUT")
		)
		(zone
			(layer "F.Cu")
			(hatch none 0.5)
			(connect_pads
				(clearance 0)
			)
			(min_thickness 0.25)
			(keepout
				(tracks allowed)
				(vias not_allowed)
				(pads allowed)
				(copperpour not_allowed)
				(footprints allowed)
			)
			(placement
				(enabled no)
				(sheetname "")
			)
			(fill
				(thermal_gap 0.5)
				(thermal_bridge_width 0.5)
				(island_removal_mode 0)
			)
			(polygon
				(pts
					(xy 124.5108 -42.8498) (xy 124.5108 -42.2402) (xy 124.6632 -42.2402) (xy 124.6632 -42.8498)
				)
			)
		)
	)
	(footprint ""
		(layer "F.Cu")
		(at 41.656 -132.461)
		(property "Reference" "SP36"
			(at 0 0 0)
			(layer "F.SilkS")
			(hide yes)
			(effects
				(font
					(size 1.27 1.27)
				)
			)
		)
		(property "Value" ""
			(at 0 0 0)
			(layer "F.Fab")
			(effects
				(font
					(size 1.27 1.27)
				)
			)
		)
		(duplicate_pad_numbers_are_jumpers no)
	)
)
